# BASEBOARD_FAB2 (Tioga Pass) — schematic netlist excerpt (pin names and nets, part order shuffled) for the footprints in the layout excerpt that follows; sources: Cadence DE-HDL packaged netlist, KiCad conversion of Wiwynn_Tioga_Pass_MB.brd

C8B13  CAP_A  22.0UF 4V 20% X6S  pkg 0603V  page 131 : A = P1V05_PCH_STBY ; B = GND
R1G12  RES  22.1 1.0% CHIP  pkg 0402  page 223 : A = PWRGD_PVDDQ_GHJ_R ; B = PWRGD_PVDDQ_GHJ
R8B3  RES  4.75K 1% CHIP  pkg 0402  page 91 : A = PVPP_ABC ; B = FM_MODPRST_HFI0_CPU0_LVT2_N

(kicad_pcb
	(version 20260206)
	(generator "pcbnew")
	(generator_version "10.0")
	(general
		(thickness 1.6)
		(legacy_teardrops no)
	)
	(paper "A4")
	(title_block
		(title "Wiwynn_Tioga_Pass_MB.brd")
		(comment 1 "Tioga Pass / footprints 1801-1803 of 4770")
	)
	(layers
		(0 "F.Cu" signal "TOP")
		(4 "In1.Cu" signal "L2GND")
		(6 "In2.Cu" signal "L3")
		(8 "In3.Cu" signal "L4GND")
		(10 "In4.Cu" signal "L5")
		(12 "In5.Cu" signal "L6GND")
		(14 "In6.Cu" signal "L7VCC")
		(16 "In7.Cu" signal "L8VCC")
		(18 "In8.Cu" signal "L9GND")
		(20 "In9.Cu" signal "L10")
		(22 "In10.Cu" signal "L11GND")
		(24 "In11.Cu" signal "L12")
		(26 "In12.Cu" signal "L13GND")
		(2 "B.Cu" signal "BOTTOM")
		(9 "F.Adhes" user "F.Adhesive")
		(11 "B.Adhes" user "B.Adhesive")
		(13 "F.Paste" user "Package Geometry/Pastemask Top")
		(15 "B.Paste" user "Package Geometry/Pastemask Bottom")
		(5 "F.SilkS" user "Ref Des/Silkscreen Top")
		(7 "B.SilkS" user "Ref Des/Silkscreen Bottom")
		(1 "F.Mask" user "Board Geometry/Soldermask Top")
		(3 "B.Mask" user "Board Geometry/Soldermask Bottom")
		(17 "Dwgs.User" user "User.Drawings")
		(19 "Cmts.User" user "User.Comments")
		(21 "Eco1.User" user "User.Eco1")
		(23 "Eco2.User" user "User.Eco2")
		(25 "Edge.Cuts" user "Board Geometry/Outline")
		(27 "Margin" user)
		(31 "F.CrtYd" user "Package Geometry/Place Bound Top")
		(29 "B.CrtYd" user "Package Geometry/Place Bound Bottom")
		(35 "F.Fab" user "Ref Des/Assembly Top")
		(33 "B.Fab" user "Ref Des/Assembly Bottom")
	)
	(footprint ""
		(layer "F.Cu")
		(at 15.293848 -0.733552 90)
		(property "Reference" "R1G12"
			(at 0 0 90)
			(layer "F.SilkS")
			(hide yes)
			(effects
				(font
					(size 1.27 1.27)
				)
			)
		)
		(property "Value" ""
			(at 0 0 90)
			(layer "F.Fab")
			(effects
				(font
					(size 1.27 1.27)
				)
			)
		)
		(duplicate_pad_numbers_are_jumpers no)
		(fp_rect
			(start 0.2794 -0.1016)
			(end -0.2794 0.9906)
			(stroke
				(width 0)
				(type default)
			)
			(fill no)
			(layer "F.CrtYd")
		)
		(fp_line
			(start 0.2794 -0.1016)
			(end -0.2794 -0.1016)
			(stroke
				(width 0.1)
				(type default)
			)
			(layer "F.Fab")
		)
		(fp_line
			(start -0.2794 -0.1016)
			(end -0.2794 0.9906)
			(stroke
				(width 0.1)
				(type default)
			)
			(layer "F.Fab")
		)
		(fp_line
			(start 0.2794 0.9906)
			(end 0.2794 -0.1016)
			(stroke
				(width 0.1)
				(type default)
			)
			(layer "F.Fab")
		)
		(fp_line
			(start -0.2794 0.9906)
			(end 0.2794 0.9906)
			(stroke
				(width 0.1)
				(type default)
			)
			(layer "F.Fab")
		)
		(pad "1" smd rect
			(at 0 0 90)
			(size 0.508 0.508)
			(layers "F.Cu" "F.Mask" "F.Paste")
			(net "PWRGD_PVDDQ_GHJ_R")
		)
		(pad "2" smd rect
			(at 0 0.889 90)
			(size 0.508 0.508)
			(layers "F.Cu" "F.Mask" "F.Paste")
			(net "PWRGD_PVDDQ_GHJ")
		)
		(zone
			(layer "F.Cu")
			(hatch none 0.5)
			(connect_pads
				(clearance 0)
			)
			(min_thickness 0.25)
			(keepout
				(tracks allowed)
				(vias not_allowed)
				(pads allowed)
				(copperpour not_allowed)
				(footprints allowed)
			)
			(placement
				(enabled no)
				(sheetname "")
			)
			(fill
				(thermal_gap 0.5)
				(thermal_bridge_width 0.5)
				(island_removal_mode 0)
			)
			(polygon
				(pts
					(xy 15.547848 -0.987552) (xy 15.547848 -0.479552) (xy 15.928848 -0.479552) (xy 15.928848 -0.987552)
				)
			)
		)
		(zone
			(layer "F.Cu")
			(hatch none 0.5)
			(connect_pads
				(clearance 0)
			)
			(min_thickness 0.25)
			(keepout
				(tracks not_allowed)
				(vias allowed)
				(pads allowed)
				(copperpour not_allowed)
				(footprints allowed)
			)
			(placement
				(enabled no)
				(sheetname "")
			)
			(fill
				(thermal_gap 0.5)
				(thermal_bridge_width 0.5)
				(island_removal_mode 0)
			)
			(polygon
				(pts
					(xy 15.547848 -0.987552) (xy 15.547848 -0.479552) (xy 15.928848 -0.479552) (xy 15.928848 -0.987552)
				)
			)
		)
	)
	(footprint ""
		(layer "F.Cu")
		(at 411.444694 -132.567172 90)
		(property "Reference" "R8B3"
			(at 0 0 90)
			(layer "F.SilkS")
			(hide yes)
			(effects
				(font
					(size 1.27 1.27)
				)
			)
		)
		(property "Value" ""
			(at 0 0 90)
			(layer "F.Fab")
			(effects
				(font
					(size 1.27 1.27)
				)
			)
		)
		(duplicate_pad_numbers_are_jumpers no)
		(fp_poly
			(pts
				(xy -0.2794 -0.1016) (xy 0.2794 -0.1016) (xy 0.2794 0.9906) (xy -0.2794 0.9906)
			)
			(stroke
				(width 0)
				(type default)
			)
			(fill no)
			(layer "F.CrtYd")
		)
		(fp_line
			(start 0.2794 -0.1016)
			(end -0.2794 -0.1016)
			(stroke
				(width 0.1)
				(type default)
			)
			(layer "F.Fab")
		)
		(fp_line
			(start -0.2794 -0.1016)
			(end -0.2794 0.9906)
			(stroke
				(width 0.1)
				(type default)
			)
			(layer "F.Fab")
		)
		(fp_line
			(start 0.2794 0.9906)
			(end 0.2794 -0.1016)
			(stroke
				(width 0.1)
				(type default)
			)
			(layer "F.Fab")
		)
		(fp_line
			(start -0.2794 0.9906)
			(end 0.2794 0.9906)
			(stroke
				(width 0.1)
				(type default)
			)
			(layer "F.Fab")
		)
		(pad "1" smd rect
			(at 0 0 90)
			(size 0.508 0.508)
			(layers "F.Cu" "F.Mask" "F.Paste")
			(net "PVPP_ABC")
		)
		(pad "2" smd rect
			(at 0 0.889 90)
			(size 0.508 0.508)
			(layers "F.Cu" "F.Mask" "F.Paste")
			(net "FM_MODPRST_HFI0_CPU0_LVT2_N")
		)
		(zone
			(layer "F.Cu")
			(hatch none 0.5)
			(connect_pads
				(clearance 0)
			)
			(min_thickness 0.25)
			(keepout
				(tracks allowed)
				(vias not_allowed)
				(pads allowed)
				(copperpour not_allowed)
				(footprints allowed)
			)
			(placement
				(enabled no)
				(sheetname "")
			)
			(fill
				(thermal_gap 0.5)
				(thermal_bridge_width 0.5)
				(island_removal_mode 0)
			)
			(polygon
				(pts
					(xy 411.698694 -132.313172) (xy 411.698694 -132.821172) (xy 412.079694 -132.821172) (xy 412.079694 -132.313172)
				)
			)
		)
		(zone
			(layer "F.Cu")
			(hatch none 0.5)
			(connect_pads
				(clearance 0)
			)
			(min_thickness 0.25)
			(keepout
				(tracks not_allowed)
				(vias allowed)
				(pads allowed)
				(copperpour not_allowed)
				(footprints allowed)
			)
			(placement
				(enabled no)
				(sheetname "")
			)
			(fill
				(thermal_gap 0.5)
				(thermal_bridge_width 0.5)
				(island_removal_mode 0)
			)
			(polygon
				(pts
					(xy 412.079694 -132.313172) (xy 412.079694 -132.821172) (xy 411.698694 -132.821172) (xy 411.698694 -132.313172)
				)
			)
		)
	)
	(footprint ""
		(layer "F.Cu")
		(at 405.1935 -116.967 90)
		(property "Reference" "C8B13"
			(at 0 0 90)
			(layer "F.SilkS")
			(hide yes)
			(effects
				(font
					(size 1.27 1.27)
				)
			)
		)
		(property "Value" ""
			(at 0 0 90)
			(layer "F.Fab")
			(effects
				(font
					(size 1.27 1.27)
				)
			)
		)
		(duplicate_pad_numbers_are_jumpers no)
		(fp_poly
			(pts
				(xy -0.4953 -0.2032) (xy 0.4953 -0.2032) (xy 0.4953 1.6002) (xy -0.4953 1.6002)
			)
			(stroke
				(width 0)
				(type default)
			)
			(fill no)
			(layer "F.CrtYd")
		)
		(fp_line
			(start 0.4953 -0.2032)
			(end 0.4953 1.6002)
			(stroke
				(width 0.1)
				(type default)
			)
			(layer "F.Fab")
		)
		(fp_line
			(start -0.4953 -0.2032)
			(end 0.4953 -0.2032)
			(stroke
				(width 0.1)
				(type default)
			)
			(layer "F.Fab")
		)
		(fp_line
			(start 0.4953 1.6002)
			(end -0.4953 1.6002)
			(stroke
				(width 0.1)
				(type default)
			)
			(layer "F.Fab")
		)
		(fp_line
			(start -0.4953 1.6002)
			(end -0.4953 -0.2032)
			(stroke
				(width 0.1)
				(type default)
			)
			(layer "F.Fab")
		)
		(pad "1" smd rect
			(at 0 0 90)
			(size 0.762 0.889)
			(layers "F.Cu" "F.Mask" "F.Paste")
			(net "P1V05_PCH_STBY")
		)
		(pad "2" smd rect
			(at 0 1.397 90)
			(size 0.762 0.889)
			(layers "F.Cu" "F.Mask" "F.Paste")
			(net "GND")
		)
		(zone
			(layer "F.Cu")
			(hatch none 0.5)
			(connect_pads
				(clearance 0)
			)
			(min_thickness 0.25)
			(keepout
				(tracks not_allowed)
				(vias allowed)
				(pads allowed)
				(copperpour not_allowed)
				(footprints allowed)
			)
			(placement
				(enabled no)
				(sheetname "")
			)
			(fill
				(thermal_gap 0.5)
				(thermal_bridge_width 0.5)
				(island_removal_mode 0)
			)
			(polygon
				(pts
					(xy 405.638 -116.586) (xy 405.638 -117.348) (xy 406.146 -117.348) (xy 406.146 -116.586)
				)
			)
		)
	)
)
